(kicad_pcb
	(version 20260206)
	(generator "pcbnew")
	(generator_version "10.0")
	(general
		(thickness 1.6)
		(legacy_teardrops no)
	)
	(paper "A4")
	(title_block
		(title "v2-pdb — ms_pdb_v2.brd")
		(comment 1 "Open CloudServer (Microsoft) / footprints 224-225 of 348")
	)
	(layers
		(0 "F.Cu" signal "TOP")
		(4 "In1.Cu" signal "GND")
		(6 "In2.Cu" signal "IN1")
		(8 "In3.Cu" signal "VCC")
		(10 "In4.Cu" signal "VCC1")
		(12 "In5.Cu" signal "IN2")
		(14 "In6.Cu" signal "GND1")
		(2 "B.Cu" signal "BOTTOM")
		(9 "F.Adhes" user "F.Adhesive")
		(11 "B.Adhes" user "B.Adhesive")
		(13 "F.Paste" user "Package Geometry/Pastemask Top")
		(15 "B.Paste" user "Package Geometry/Pastemask Bottom")
		(5 "F.SilkS" user "Ref Des/Silkscreen Top")
		(7 "B.SilkS" user "Ref Des/Silkscreen Bottom")
		(1 "F.Mask" user "Board Geometry/Soldermask Top")
		(3 "B.Mask" user "Board Geometry/Soldermask Bottom")
		(17 "Dwgs.User" user "User.Drawings")
		(19 "Cmts.User" user "User.Comments")
		(21 "Eco1.User" user "User.Eco1")
		(23 "Eco2.User" user "User.Eco2")
		(25 "Edge.Cuts" user "Board Geometry/Outline")
		(27 "Margin" user)
		(31 "F.CrtYd" user "Package Geometry/Place Bound Top")
		(29 "B.CrtYd" user "Package Geometry/Place Bound Bottom")
		(35 "F.Fab" user "Ref Des/Assembly Top")
		(33 "B.Fab" user "Ref Des/Assembly Bottom")
	)
	(footprint ""
		(layer "F.Cu")
		(at 30.45968 -171.729908)
		(property "Reference" "J2"
			(at 7.63778 3.119628 0)
			(unlocked yes)
			(layer "F.SilkS")
			(effects
				(font
					(size 0.7874 0.5842)
					(thickness 0.1524)
				)
				(justify left)
			)
		)
		(property "Value" ""
			(at 0 0 0)
			(layer "F.Fab")
			(effects
				(font
					(size 1.27 1.27)
				)
			)
		)
		(duplicate_pad_numbers_are_jumpers no)
		(fp_line
			(start -2.135124 -4.560062)
			(end -2.135124 83.300062)
			(stroke
				(width 0.1524)
				(type default)
			)
			(layer "F.SilkS")
		)
		(fp_line
			(start -2.135124 83.300062)
			(end 7.215124 83.300062)
			(stroke
				(width 0.1524)
				(type default)
			)
			(layer "F.SilkS")
		)
		(fp_line
			(start 7.215124 -4.560062)
			(end -2.135124 -4.560062)
			(stroke
				(width 0.1524)
				(type default)
			)
			(layer "F.SilkS")
		)
		(fp_line
			(start 7.215124 83.300062)
			(end 7.215124 -4.560062)
			(stroke
				(width 0.1524)
				(type default)
			)
			(layer "F.SilkS")
		)
		(fp_poly
			(pts
				(xy -2.557272 -0.130556) (xy -5.257292 -0.83058) (xy -5.257292 0.569468)
			)
			(stroke
				(width 0)
				(type default)
			)
			(fill yes)
			(layer "F.SilkS")
		)
		(fp_poly
			(pts
				(xy -2.28219 -0.127) (xy -4.98221 -0.827024) (xy -4.98221 0.573024)
			)
			(stroke
				(width 0)
				(type default)
			)
			(fill yes)
			(layer "B.SilkS")
		)
		(fp_poly
			(pts
				(xy -0.8636 -0.8636) (xy -0.8636 79.6036) (xy -0.8636 79.629) (xy 5.9436 79.629) (xy 5.9436 79.6036)
				(xy 5.9436 -0.8636) (xy 5.9436 -0.889) (xy -0.8636 -0.889)
			)
			(stroke
				(width 0)
				(type default)
			)
			(fill no)
			(layer "B.CrtYd")
		)
		(fp_rect
			(start -2.135124 -4.560062)
			(end 7.21487 83.300062)
			(stroke
				(width 0)
				(type default)
			)
			(fill no)
			(layer "F.CrtYd")
		)
		(fp_line
			(start -2.135124 -4.560062)
			(end 7.215124 -4.560062)
			(stroke
				(width 0.1)
				(type default)
			)
			(layer "F.Fab")
		)
		(fp_line
			(start -2.135124 83.300062)
			(end -2.135124 -4.560062)
			(stroke
				(width 0.1)
				(type default)
			)
			(layer "F.Fab")
		)
		(fp_line
			(start 7.215124 -4.560062)
			(end 7.215124 83.300062)
			(stroke
				(width 0.1)
				(type default)
			)
			(layer "F.Fab")
		)
		(fp_line
			(start 7.215124 83.300062)
			(end -2.135124 83.300062)
			(stroke
				(width 0.1)
				(type default)
			)
			(layer "F.Fab")
		)
		(fp_text user "32"
			(at -3.674872 78.298802 0)
			(unlocked yes)
			(layer "F.SilkS")
			(effects
				(font
					(size 0.7874 0.5842)
					(thickness 0.1524)
				)
				(justify left)
			)
		)
		(fp_text user "1"
			(at -3.253994 -1.297178 0)
			(unlocked yes)
			(layer "F.SilkS")
			(effects
				(font
					(size 0.7874 0.5842)
					(thickness 0.1524)
				)
				(justify left)
			)
		)
		(fp_text user "64"
			(at 7.640066 -0.704342 0)
			(unlocked yes)
			(layer "F.SilkS")
			(effects
				(font
					(size 0.7874 0.5842)
					(thickness 0.1524)
				)
				(justify left)
			)
		)
		(fp_text user "33"
			(at 7.654544 83.258914 0)
			(unlocked yes)
			(layer "F.SilkS")
			(effects
				(font
					(size 0.7874 0.5842)
					(thickness 0.1524)
				)
				(justify left)
			)
		)
		(fp_text user "1"
			(at -1.619758 -0.610362 0)
			(unlocked yes)
			(layer "B.SilkS")
			(effects
				(font
					(size 0.7874 0.5842)
					(thickness 0.1524)
				)
				(justify left mirror)
			)
		)
		(fp_text user "32"
			(at -1.102868 78.932024 0)
			(unlocked yes)
			(layer "B.SilkS")
			(effects
				(font
					(size 0.7874 0.5842)
					(thickness 0.1524)
				)
				(justify left mirror)
			)
		)
		(fp_text user "64"
			(at 5.791454 -1.569466 0)
			(unlocked yes)
			(layer "B.SilkS")
			(effects
				(font
					(size 0.7874 0.5842)
					(thickness 0.1524)
				)
				(justify left mirror)
			)
		)
		(fp_text user "33"
			(at 6.84784 83.378294 0)
			(unlocked yes)
			(layer "B.SilkS")
			(effects
				(font
					(size 0.7874 0.5842)
					(thickness 0.1524)
				)
				(justify left mirror)
			)
		)
		(pad "1" thru_hole rect
			(at 0 0 270)
			(size 1.6256 1.6256)
			(drill 1.1176)
			(layers "*.Cu" "*.Mask")
			(remove_unused_layers no)
			(net "P12V")
			(clearance 0)
			(padstack
				(mode front_inner_back)
				(layer "Inner"
					(shape circle)
					(size 1.6256 1.6256)
					(clearance 0)
				)
				(layer "B.Cu"
					(shape rect)
					(size 1.6256 1.6256)
					(clearance 0)
				)
			)
		)
		(pad "2" thru_hole circle
			(at 0 2.54 270)
			(size 1.6256 1.6256)
			(drill 1.1176)
			(layers "*.Cu" "*.Mask")
			(remove_unused_layers no)
			(net "P12V")
			(clearance 0)
		)
		(pad "3" thru_hole circle
			(at 0 5.08 270)
			(size 1.6256 1.6256)
			(drill 1.1176)
			(layers "*.Cu" "*.Mask")
			(remove_unused_layers no)
			(net "P12V")
			(clearance 0)
		)
		(pad "4" thru_hole circle
			(at 0 7.62 270)
			(size 1.6256 1.6256)
			(drill 1.1176)
			(layers "*.Cu" "*.Mask")
			(remove_unused_layers no)
			(net "P12V")
			(clearance 0)
		)
		(pad "5" thru_hole circle
			(at 0 10.16 270)
			(size 1.6256 1.6256)
			(drill 1.1176)
			(layers "*.Cu" "*.Mask")
			(remove_unused_layers no)
			(net "P12V")
			(clearance 0)
		)
		(pad "6" thru_hole circle
			(at 0 12.7 270)
			(size 1.6256 1.6256)
			(drill 1.1176)
			(layers "*.Cu" "*.Mask")
			(remove_unused_layers no)
			(net "P12V")
			(clearance 0)
		)
		(pad "7" thru_hole circle
			(at 0 15.24 270)
			(size 1.6256 1.6256)
			(drill 1.1176)
			(layers "*.Cu" "*.Mask")
			(remove_unused_layers no)
			(net "P12V")
			(clearance 0)
		)
		(pad "8" thru_hole circle
			(at 0 17.78 270)
			(size 1.6256 1.6256)
			(drill 1.1176)
			(layers "*.Cu" "*.Mask")
			(remove_unused_layers no)
			(net "P12V")
			(clearance 0)
		)
		(pad "9" thru_hole circle
			(at 0 20.32 270)
			(size 1.6256 1.6256)
			(drill 1.1176)
			(layers "*.Cu" "*.Mask")
			(remove_unused_layers no)
			(net "P12V")
			(clearance 0)
		)
		(pad "10" thru_hole circle
			(at 0 22.86 270)
			(size 1.6256 1.6256)
			(drill 1.1176)
			(layers "*.Cu" "*.Mask")
			(remove_unused_layers no)
			(net "P12V")
			(clearance 0)
		)
		(pad "11" thru_hole circle
			(at 0 25.4 270)
			(size 1.6256 1.6256)
			(drill 1.1176)
			(layers "*.Cu" "*.Mask")
			(remove_unused_layers no)
			(net "P12V")
			(clearance 0)
		)
		(pad "12" thru_hole circle
			(at 0 27.94 270)
			(size 1.6256 1.6256)
			(drill 1.1176)
			(layers "*.Cu" "*.Mask")
			(remove_unused_layers no)
			(net "P12V")
			(clearance 0)
		)
		(pad "13" thru_hole circle
			(at 0 30.48 270)
			(size 1.6256 1.6256)
			(drill 1.1176)
			(layers "*.Cu" "*.Mask")
			(remove_unused_layers no)
			(net "GND")
			(clearance 0)
		)
		(pad "14" thru_hole circle
			(at 0 33.02 270)
			(size 1.6256 1.6256)
			(drill 1.1176)
			(layers "*.Cu" "*.Mask")
			(remove_unused_layers no)
			(net "GND")
			(clearance 0)
		)
		(pad "15" thru_hole circle
			(at 0 35.56 270)
			(size 1.6256 1.6256)
			(drill 1.1176)
			(layers "*.Cu" "*.Mask")
			(remove_unused_layers no)
			(net "GND")
			(clearance 0)
		)
		(pad "16" thru_hole circle
			(at 0 38.1 270)
			(size 1.6256 1.6256)
			(drill 1.1176)
			(layers "*.Cu" "*.Mask")
			(remove_unused_layers no)
			(net "GND")
			(clearance 0)
		)
		(pad "17" thru_hole circle
			(at 0 40.64 270)
			(size 1.6256 1.6256)
			(drill 1.1176)
			(layers "*.Cu" "*.Mask")
			(remove_unused_layers no)
			(net "GND")
			(clearance 0)
		)
		(pad "18" thru_hole circle
			(at 0 43.18 270)
			(size 1.6256 1.6256)
			(drill 1.1176)
			(layers "*.Cu" "*.Mask")
			(remove_unused_layers no)
			(net "GND")
			(clearance 0)
		)
		(pad "19" thru_hole circle
			(at 0 45.72 270)
			(size 1.6256 1.6256)
			(drill 1.1176)
			(layers "*.Cu" "*.Mask")
			(remove_unused_layers no)
			(net "GND")
			(clearance 0)
		)
		(pad "20" thru_hole circle
			(at 0 48.26 270)
			(size 1.6256 1.6256)
			(drill 1.1176)
			(layers "*.Cu" "*.Mask")
			(remove_unused_layers no)
			(net "GND")
			(clearance 0)
		)
		(pad "21" thru_hole circle
			(at 0 50.8 270)
			(size 1.6256 1.6256)
			(drill 1.1176)
			(layers "*.Cu" "*.Mask")
			(remove_unused_layers no)
			(net "GND")
			(clearance 0)
		)
		(pad "22" thru_hole circle
			(at 0 53.34 270)
			(size 1.6256 1.6256)
			(drill 1.1176)
			(layers "*.Cu" "*.Mask")
			(remove_unused_layers no)
			(net "GND")
			(clearance 0)
		)
		(pad "23" thru_hole circle
			(at 0 55.88 270)
			(size 1.6256 1.6256)
			(drill 1.1176)
			(layers "*.Cu" "*.Mask")
			(remove_unused_layers no)
			(net "GND")
			(clearance 0)
		)
		(pad "24" thru_hole circle
			(at 0 58.42 270)
			(size 1.6256 1.6256)
			(drill 1.1176)
			(layers "*.Cu" "*.Mask")
			(remove_unused_layers no)
			(net "GND")
			(clearance 0)
		)
		(pad "25" thru_hole circle
			(at 0 60.96 270)
			(size 1.6256 1.6256)
			(drill 1.1176)
			(layers "*.Cu" "*.Mask")
			(remove_unused_layers no)
			(net "PHLOSS")
			(clearance 0)
		)
		(pad "26" thru_hole circle
			(at 0 63.5 270)
			(size 1.6256 1.6256)
			(drill 1.1176)
			(layers "*.Cu" "*.Mask")
			(remove_unused_layers no)
			(net "PSU2_REMOTE_N")
			(clearance 0)
		)
		(pad "27" thru_hole circle
			(at 0 66.04 270)
			(size 1.6256 1.6256)
			(drill 1.1176)
			(layers "*.Cu" "*.Mask")
			(remove_unused_layers no)
			(net "PSU2_AC_OK")
			(clearance 0)
		)
		(pad "28" thru_hole circle
			(at 0 68.58 270)
			(size 1.6256 1.6256)
			(drill 1.1176)
			(layers "*.Cu" "*.Mask")
			(remove_unused_layers no)
			(net "PSU2_CSAHRE")
			(clearance 0)
		)
		(pad "29" thru_hole circle
			(at 0 71.12 270)
			(size 1.6256 1.6256)
			(drill 1.1176)
			(layers "*.Cu" "*.Mask")
			(remove_unused_layers no)
			(net "PSU2_PS_ON_N")
			(clearance 0)
		)
		(pad "30" thru_hole circle
			(at 0 73.66 270)
			(size 1.6256 1.6256)
			(drill 1.1176)
			(layers "*.Cu" "*.Mask")
			(remove_unused_layers no)
			(net "PSU2_PS_KILL")
			(clearance 0)
		)
		(pad "31" thru_hole circle
			(at 0 76.2 270)
			(size 1.6256 1.6256)
			(drill 1.1176)
			(layers "*.Cu" "*.Mask")
			(remove_unused_layers no)
			(net "PSU2_RESET")
			(clearance 0)
		)
		(pad "32" thru_hole circle
			(at 0 78.74 270)
			(size 1.6256 1.6256)
			(drill 1.1176)
			(layers "*.Cu" "*.Mask")
			(remove_unused_layers no)
			(net "PSU_ALERT_N")
			(clearance 0)
		)
		(pad "33" thru_hole circle
			(at 5.08 78.74 270)
			(size 1.6256 1.6256)
			(drill 1.1176)
			(layers "*.Cu" "*.Mask")
			(remove_unused_layers no)
			(net "I2C_PSU1_SDA")
			(clearance 0)
		)
		(pad "34" thru_hole circle
			(at 5.08 76.2 270)
			(size 1.6256 1.6256)
			(drill 1.1176)
			(layers "*.Cu" "*.Mask")
			(remove_unused_layers no)
			(net "Net_429")
			(clearance 0)
		)
		(pad "35" thru_hole circle
			(at 5.08 73.66 270)
			(size 1.6256 1.6256)
			(drill 1.1176)
			(layers "*.Cu" "*.Mask")
			(remove_unused_layers no)
			(net "I2C_PSU1_SCL")
			(clearance 0)
		)
		(pad "36" thru_hole circle
			(at 5.08 71.12 270)
			(size 1.6256 1.6256)
			(drill 1.1176)
			(layers "*.Cu" "*.Mask")
			(remove_unused_layers no)
			(net "PSU2_RETURN")
			(clearance 0)
		)
		(pad "37" thru_hole circle
			(at 5.08 68.58 270)
			(size 1.6256 1.6256)
			(drill 1.1176)
			(layers "*.Cu" "*.Mask")
			(remove_unused_layers no)
			(net "PSU2_DC_OK")
			(clearance 0)
		)
		(pad "38" thru_hole circle
			(at 5.08 66.04 270)
			(size 1.6256 1.6256)
			(drill 1.1176)
			(layers "*.Cu" "*.Mask")
			(remove_unused_layers no)
			(net "PSU2_AD0")
			(clearance 0)
		)
		(pad "39" thru_hole circle
			(at 5.08 63.5 270)
			(size 1.6256 1.6256)
			(drill 1.1176)
			(layers "*.Cu" "*.Mask")
			(remove_unused_layers no)
			(net "P12V_STBY")
			(clearance 0)
		)
		(pad "40" thru_hole circle
			(at 5.08 60.96 270)
			(size 1.6256 1.6256)
			(drill 1.1176)
			(layers "*.Cu" "*.Mask")
			(remove_unused_layers no)
			(net "PSU2_REMOTE_P")
			(clearance 0)
		)
		(pad "41" thru_hole circle
			(at 5.08 58.42 270)
			(size 1.6256 1.6256)
			(drill 1.1176)
			(layers "*.Cu" "*.Mask")
			(remove_unused_layers no)
			(net "GND")
			(clearance 0)
		)
		(pad "42" thru_hole circle
			(at 5.08 55.88 270)
			(size 1.6256 1.6256)
			(drill 1.1176)
			(layers "*.Cu" "*.Mask")
			(remove_unused_layers no)
			(net "GND")
			(clearance 0)
		)
		(pad "43" thru_hole circle
			(at 5.08 53.34 270)
			(size 1.6256 1.6256)
			(drill 1.1176)
			(layers "*.Cu" "*.Mask")
			(remove_unused_layers no)
			(net "GND")
			(clearance 0)
		)
		(pad "44" thru_hole circle
			(at 5.08 50.8 270)
			(size 1.6256 1.6256)
			(drill 1.1176)
			(layers "*.Cu" "*.Mask")
			(remove_unused_layers no)
			(net "GND")
			(clearance 0)
		)
		(pad "45" thru_hole circle
			(at 5.08 48.26 270)
			(size 1.6256 1.6256)
			(drill 1.1176)
			(layers "*.Cu" "*.Mask")
			(remove_unused_layers no)
			(net "GND")
			(clearance 0)
		)
		(pad "46" thru_hole circle
			(at 5.08 45.72 270)
			(size 1.6256 1.6256)
			(drill 1.1176)
			(layers "*.Cu" "*.Mask")
			(remove_unused_layers no)
			(net "GND")
			(clearance 0)
		)
		(pad "47" thru_hole circle
			(at 5.08 43.18 270)
			(size 1.6256 1.6256)
			(drill 1.1176)
			(layers "*.Cu" "*.Mask")
			(remove_unused_layers no)
			(net "GND")
			(clearance 0)
		)
		(pad "48" thru_hole circle
			(at 5.08 40.64 270)
			(size 1.6256 1.6256)
			(drill 1.1176)
			(layers "*.Cu" "*.Mask")
			(remove_unused_layers no)
			(net "GND")
			(clearance 0)
		)
		(pad "49" thru_hole circle
			(at 5.08 38.1 270)
			(size 1.6256 1.6256)
			(drill 1.1176)
			(layers "*.Cu" "*.Mask")
			(remove_unused_layers no)
			(net "GND")
			(clearance 0)
		)
		(pad "50" thru_hole circle
			(at 5.08 35.56 270)
			(size 1.6256 1.6256)
			(drill 1.1176)
			(layers "*.Cu" "*.Mask")
			(remove_unused_layers no)
			(net "GND")
			(clearance 0)
		)
		(pad "51" thru_hole circle
			(at 5.08 33.02 270)
			(size 1.6256 1.6256)
			(drill 1.1176)
			(layers "*.Cu" "*.Mask")
			(remove_unused_layers no)
			(net "GND")
			(clearance 0)
		)
		(pad "52" thru_hole circle
			(at 5.08 30.48 270)
			(size 1.6256 1.6256)
			(drill 1.1176)
			(layers "*.Cu" "*.Mask")
			(remove_unused_layers no)
			(net "GND")
			(clearance 0)
		)
		(pad "53" thru_hole circle
			(at 5.08 27.94 270)
			(size 1.6256 1.6256)
			(drill 1.1176)
			(layers "*.Cu" "*.Mask")
			(remove_unused_layers no)
			(net "P12V")
			(clearance 0)
		)
		(pad "54" thru_hole circle
			(at 5.08 25.4 270)
			(size 1.6256 1.6256)
			(drill 1.1176)
			(layers "*.Cu" "*.Mask")
			(remove_unused_layers no)
			(net "P12V")
			(clearance 0)
		)
		(pad "55" thru_hole circle
			(at 5.08 22.86 270)
			(size 1.6256 1.6256)
			(drill 1.1176)
			(layers "*.Cu" "*.Mask")
			(remove_unused_layers no)
			(net "P12V")
			(clearance 0)
		)
		(pad "56" thru_hole circle
			(at 5.08 20.32 270)
			(size 1.6256 1.6256)
			(drill 1.1176)
			(layers "*.Cu" "*.Mask")
			(remove_unused_layers no)
			(net "P12V")
			(clearance 0)
		)
		(pad "57" thru_hole circle
			(at 5.08 17.78 270)
			(size 1.6256 1.6256)
			(drill 1.1176)
			(layers "*.Cu" "*.Mask")
			(remove_unused_layers no)
			(net "P12V")
			(clearance 0)
		)
		(pad "58" thru_hole circle
			(at 5.08 15.24 270)
			(size 1.6256 1.6256)
			(drill 1.1176)
			(layers "*.Cu" "*.Mask")
			(remove_unused_layers no)
			(net "P12V")
			(clearance 0)
		)
		(pad "59" thru_hole circle
			(at 5.08 12.7 270)
			(size 1.6256 1.6256)
			(drill 1.1176)
			(layers "*.Cu" "*.Mask")
			(remove_unused_layers no)
			(net "P12V")
			(clearance 0)
		)
		(pad "60" thru_hole circle
			(at 5.08 10.16 270)
			(size 1.6256 1.6256)
			(drill 1.1176)
			(layers "*.Cu" "*.Mask")
			(remove_unused_layers no)
			(net "P12V")
			(clearance 0)
		)
		(pad "61" thru_hole circle
			(at 5.08 7.62 270)
			(size 1.6256 1.6256)
			(drill 1.1176)
			(layers "*.Cu" "*.Mask")
			(remove_unused_layers no)
			(net "P12V")
			(clearance 0)
		)
		(pad "62" thru_hole circle
			(at 5.08 5.08 270)
			(size 1.6256 1.6256)
			(drill 1.1176)
			(layers "*.Cu" "*.Mask")
			(remove_unused_layers no)
			(net "P12V")
			(clearance 0)
		)
		(pad "63" thru_hole circle
			(at 5.08 2.54 270)
			(size 1.6256 1.6256)
			(drill 1.1176)
			(layers "*.Cu" "*.Mask")
			(remove_unused_layers no)
			(net "P12V")
			(clearance 0)
		)
		(pad "64" thru_hole circle
			(at 5.08 0 270)
			(size 1.6256 1.6256)
			(drill 1.1176)
			(layers "*.Cu" "*.Mask")
			(remove_unused_layers no)
			(net "P12V")
			(clearance 0)
		)
	)
	(footprint ""
		(layer "F.Cu")
		(at 22.524974 -177.804572 -90)
		(property "Reference" "R160"
			(at 1.072896 4.462526 90)
			(unlocked yes)
			(layer "F.SilkS")
			(effects
				(font
					(size 0.7874 0.5842)
					(thickness 0.1524)
				)
				(justify left)
			)
		)
		(property "Value" ""
			(at 0 0 270)
			(layer "F.Fab")
			(effects
				(font
					(size 1.27 1.27)
				)
			)
		)
		(duplicate_pad_numbers_are_jumpers no)
		(fp_line
			(start -0.7874 0.4064)
			(end -0.7874 -0.4064)
			(stroke
				(width 0.1524)
				(type default)
			)
			(layer "F.SilkS")
		)
		(fp_line
			(start 0.7874 0.4064)
			(end -0.7874 0.4064)
			(stroke
				(width 0.1524)
				(type default)
			)
			(layer "F.SilkS")
		)
		(fp_line
			(start -0.7874 -0.4064)
			(end 0.7874 -0.4064)
			(stroke
				(width 0.1524)
				(type default)
			)
			(layer "F.SilkS")
		)
		(fp_line
			(start 0.7874 -0.4064)
			(end 0.7874 0.4064)
			(stroke
				(width 0.1524)
				(type default)
			)
			(layer "F.SilkS")
		)
		(fp_poly
			(pts
				(xy -0.508 0.2794) (xy -0.508 0.2286) (xy -0.635 0.2286) (xy -0.635 -0.254) (xy -0.5334 -0.254)
				(xy -0.5334 -0.2794) (xy 0.5334 -0.2794) (xy 0.5334 -0.254) (xy 0.635 -0.254) (xy 0.635 0.254) (xy 0.5334 0.254)
				(xy 0.5334 0.2794)
			)
			(stroke
				(width 0)
				(type default)
			)
			(fill no)
			(layer "F.CrtYd")
		)
		(pad "1" smd rect
			(at 0.40005 0 270)
			(size 0.4572 0.508)
			(layers "F.Cu" "F.Mask" "F.Paste")
			(net "N42264085")
		)
		(pad "2" smd rect
			(at -0.40005 0 270)
			(size 0.4572 0.508)
			(layers "F.Cu" "F.Mask" "F.Paste")
			(net "GND")
		)
	)
)
